(kicad_pcb
	(version 20221018)
	(generator pcbnew)
	(general
    (thickness 1.62)
  )
	(paper "A4")
	(title_block
    (title "ECP5 - Datacenter Secure Control Module (DC-SCM)")
    (date "2024-07-01")
    (rev "1.2.1")
		(comment 9 "footprints 304-311 of 506")
	)
	(layers
    (0 "F.Cu" signal)
    (1 "In1.Cu" power)
    (2 "In2.Cu" signal)
    (3 "In3.Cu" power)
    (4 "In4.Cu" power)
    (5 "In5.Cu" signal)
    (6 "In6.Cu" power)
    (31 "B.Cu" signal)
    (32 "B.Adhes" user "B.Adhesive")
    (33 "F.Adhes" user "F.Adhesive")
    (34 "B.Paste" user)
    (35 "F.Paste" user)
    (36 "B.SilkS" user "B.Silkscreen")
    (37 "F.SilkS" user "F.Silkscreen")
    (38 "B.Mask" user)
    (39 "F.Mask" user)
    (40 "Dwgs.User" user "User.Drawings")
    (41 "Cmts.User" user "User.Comments")
    (42 "Eco1.User" user "User.Eco1")
    (43 "Eco2.User" user "User.Eco2")
    (44 "Edge.Cuts" user)
    (45 "Margin" user)
    (46 "B.CrtYd" user "B.Courtyard")
    (47 "F.CrtYd" user "F.Courtyard")
    (48 "B.Fab" user)
    (49 "F.Fab" user)
  )
	(footprint "antmicro-footprints:C_0402_1005Metric" (layer "B.Cu")
    (at 102.95 132.235 90)
    (descr "Capacitor SMD 0402")
    (tags "capacitor SMD 0402")
    (property "Author" "Antmicro")
    (property "Dielectric" "")
    (property "License" "Apache-2.0")
    (property "MPN" "C1005X5R1E474M050BB")
    (property "Manufacturer" "TDK")
    (property "Public" "False")
    (property "Sheetfile" "fpga-power-supply.kicad_sch")
    (property "Sheetname" "FPGA power supply")
    (property "Val" "470n")
    (property "Voltage" "")
    (property "ki_description" "SMD Multilayer Ceramic Capacitor, 0.47 µF, 25 V, 0402 [1005 Metric], ± 20%, X5R, C")
    (property "ki_keywords" "0402, SMT, CAPACITOR, PASSIVE, CERAMIC, MLCC")
    (attr smd)
    (fp_text reference "C184" (at -20.78 0.91 90) (layer "B.SilkS")
        (effects (font (size 0.7 0.7) (thickness 0.127)) (justify mirror))
    )
    (fp_text value "C_470n_0402" (at 0 -1.17 90) (layer "B.Fab")
        (effects (font (size 1 1) (thickness 0.15)) (justify mirror))
    )
    (fp_text user "${REFERENCE}" (at 0 0 90) (layer "B.Fab")
        (effects (font (size 0.25 0.25) (thickness 0.04)) (justify mirror))
    )
    (fp_text user "Author: Antmicro" (at -0.939 -3.399 270) (layer "B.Fab") hide
        (effects (font (size 0.7 0.7) (thickness 0.15)) (justify left bottom mirror))
    )
    (fp_text user "License: Apache-2.0" (at -0.939 -5.799 270) (layer "B.Fab") hide
        (effects (font (size 0.7 0.7) (thickness 0.15)) (justify left bottom mirror))
    )
    (fp_rect (start -0.925 0.47) (end 0.925 -0.47)
      (stroke (width 0.05) (type default)) (fill none) (layer "B.CrtYd"))
    (fp_line (start -0.494 -0.248) (end -0.494 0.25)
      (stroke (width 0.15) (type solid)) (layer "B.Fab"))
    (fp_line (start -0.494 0.25) (end 0.504 0.25)
      (stroke (width 0.15) (type solid)) (layer "B.Fab"))
    (fp_line (start 0.504 -0.248) (end -0.494 -0.248)
      (stroke (width 0.15) (type solid)) (layer "B.Fab"))
    (fp_line (start 0.504 0.25) (end 0.504 -0.248)
      (stroke (width 0.15) (type solid)) (layer "B.Fab"))
    (pad "1" smd roundrect (at -0.48 0 90) (size 0.59 0.64) (layers "B.Cu" "B.Paste" "B.Mask") (roundrect_rratio 0.25)
      (net 1 "GND") (pintype "passive"))
    (pad "2" smd roundrect (at 0.48 0 90) (size 0.59 0.64) (layers "B.Cu" "B.Paste" "B.Mask") (roundrect_rratio 0.25)
      (net 304 "/FPGA power supply/VCCAUX") (pintype "passive"))
  )
	(footprint "antmicro-footprints:C_0402_1005Metric" (layer "B.Cu")
    (at 105.2 124.05 90)
    (descr "Capacitor SMD 0402")
    (tags "capacitor SMD 0402")
    (property "Author" "Antmicro")
    (property "Dielectric" "")
    (property "License" "Apache-2.0")
    (property "MPN" "C1005X5R1E474M050BB")
    (property "Manufacturer" "TDK")
    (property "Public" "False")
    (property "Sheetfile" "fpga-power-supply.kicad_sch")
    (property "Sheetname" "FPGA power supply")
    (property "Val" "470n")
    (property "Voltage" "")
    (property "ki_description" "SMD Multilayer Ceramic Capacitor, 0.47 µF, 25 V, 0402 [1005 Metric], ± 20%, X5R, C")
    (property "ki_keywords" "0402, SMT, CAPACITOR, PASSIVE, CERAMIC, MLCC")
    (attr smd)
    (fp_text reference "C185" (at -22.005 0.43 90) (layer "B.SilkS")
        (effects (font (size 0.7 0.7) (thickness 0.127)) (justify mirror))
    )
    (fp_text value "C_470n_0402" (at 0 -1.17 90) (layer "B.Fab")
        (effects (font (size 1 1) (thickness 0.15)) (justify mirror))
    )
    (fp_text user "License: Apache-2.0" (at -0.939 -5.799 270) (layer "B.Fab") hide
        (effects (font (size 0.7 0.7) (thickness 0.15)) (justify left bottom mirror))
    )
    (fp_text user "${REFERENCE}" (at 0 0 90) (layer "B.Fab")
        (effects (font (size 0.25 0.25) (thickness 0.04)) (justify mirror))
    )
    (fp_text user "Author: Antmicro" (at -0.939 -3.399 270) (layer "B.Fab") hide
        (effects (font (size 0.7 0.7) (thickness 0.15)) (justify left bottom mirror))
    )
    (fp_rect (start -0.925 0.47) (end 0.925 -0.47)
      (stroke (width 0.05) (type default)) (fill none) (layer "B.CrtYd"))
    (fp_line (start -0.494 -0.248) (end -0.494 0.25)
      (stroke (width 0.15) (type solid)) (layer "B.Fab"))
    (fp_line (start -0.494 0.25) (end 0.504 0.25)
      (stroke (width 0.15) (type solid)) (layer "B.Fab"))
    (fp_line (start 0.504 -0.248) (end -0.494 -0.248)
      (stroke (width 0.15) (type solid)) (layer "B.Fab"))
    (fp_line (start 0.504 0.25) (end 0.504 -0.248)
      (stroke (width 0.15) (type solid)) (layer "B.Fab"))
    (pad "1" smd roundrect (at -0.48 0 90) (size 0.59 0.64) (layers "B.Cu" "B.Paste" "B.Mask") (roundrect_rratio 0.25)
      (net 211 "VCC1V2") (pintype "passive"))
    (pad "2" smd roundrect (at 0.48 0 90) (size 0.59 0.64) (layers "B.Cu" "B.Paste" "B.Mask") (roundrect_rratio 0.25)
      (net 1 "GND") (pintype "passive"))
  )
	(footprint "antmicro-footprints:C_0402_1005Metric" (layer "B.Cu")
    (at 103.975 132.25 90)
    (descr "Capacitor SMD 0402")
    (tags "capacitor SMD 0402")
    (property "Author" "Antmicro")
    (property "Dielectric" "")
    (property "License" "Apache-2.0")
    (property "MPN" "C1005X5R1E474M050BB")
    (property "Manufacturer" "TDK")
    (property "Public" "False")
    (property "Sheetfile" "fpga-power-supply.kicad_sch")
    (property "Sheetname" "FPGA power supply")
    (property "Val" "470n")
    (property "Voltage" "")
    (property "ki_description" "SMD Multilayer Ceramic Capacitor, 0.47 µF, 25 V, 0402 [1005 Metric], ± 20%, X5R, C")
    (property "ki_keywords" "0402, SMT, CAPACITOR, PASSIVE, CERAMIC, MLCC")
    (attr smd)
    (fp_text reference "C186" (at -20.785 0.855 90) (layer "B.SilkS")
        (effects (font (size 0.7 0.7) (thickness 0.127)) (justify mirror))
    )
    (fp_text value "C_470n_0402" (at 0 -1.17 90) (layer "B.Fab")
        (effects (font (size 1 1) (thickness 0.15)) (justify mirror))
    )
    (fp_text user "License: Apache-2.0" (at -0.939 -5.799 270) (layer "B.Fab") hide
        (effects (font (size 0.7 0.7) (thickness 0.15)) (justify left bottom mirror))
    )
    (fp_text user "${REFERENCE}" (at 0 0 90) (layer "B.Fab")
        (effects (font (size 0.25 0.25) (thickness 0.04)) (justify mirror))
    )
    (fp_text user "Author: Antmicro" (at -0.939 -3.399 270) (layer "B.Fab") hide
        (effects (font (size 0.7 0.7) (thickness 0.15)) (justify left bottom mirror))
    )
    (fp_rect (start -0.925 0.47) (end 0.925 -0.47)
      (stroke (width 0.05) (type default)) (fill none) (layer "B.CrtYd"))
    (fp_line (start -0.494 -0.248) (end -0.494 0.25)
      (stroke (width 0.15) (type solid)) (layer "B.Fab"))
    (fp_line (start -0.494 0.25) (end 0.504 0.25)
      (stroke (width 0.15) (type solid)) (layer "B.Fab"))
    (fp_line (start 0.504 -0.248) (end -0.494 -0.248)
      (stroke (width 0.15) (type solid)) (layer "B.Fab"))
    (fp_line (start 0.504 0.25) (end 0.504 -0.248)
      (stroke (width 0.15) (type solid)) (layer "B.Fab"))
    (pad "1" smd roundrect (at -0.48 0 90) (size 0.59 0.64) (layers "B.Cu" "B.Paste" "B.Mask") (roundrect_rratio 0.25)
      (net 1 "GND") (pintype "passive"))
    (pad "2" smd roundrect (at 0.48 0 90) (size 0.59 0.64) (layers "B.Cu" "B.Paste" "B.Mask") (roundrect_rratio 0.25)
      (net 304 "/FPGA power supply/VCCAUX") (pintype "passive"))
  )
	(footprint "antmicro-footprints:C_0402_1005Metric" (layer "B.Cu")
    (at 102 124.065 90)
    (descr "Capacitor SMD 0402")
    (tags "capacitor SMD 0402")
    (property "Author" "Antmicro")
    (property "Dielectric" "")
    (property "License" "Apache-2.0")
    (property "MPN" "C1005X5R1E474M050BB")
    (property "Manufacturer" "TDK")
    (property "Public" "False")
    (property "Sheetfile" "fpga-power-supply.kicad_sch")
    (property "Sheetname" "FPGA power supply")
    (property "Val" "470n")
    (property "Voltage" "")
    (property "ki_description" "SMD Multilayer Ceramic Capacitor, 0.47 µF, 25 V, 0402 [1005 Metric], ± 20%, X5R, C")
    (property "ki_keywords" "0402, SMT, CAPACITOR, PASSIVE, CERAMIC, MLCC")
    (attr smd)
    (fp_text reference "C187" (at -22.02 -0.18 90) (layer "B.SilkS")
        (effects (font (size 0.7 0.7) (thickness 0.127)) (justify mirror))
    )
    (fp_text value "C_470n_0402" (at 0 -1.17 90) (layer "B.Fab")
        (effects (font (size 1 1) (thickness 0.15)) (justify mirror))
    )
    (fp_text user "License: Apache-2.0" (at -0.939 -5.799 270) (layer "B.Fab") hide
        (effects (font (size 0.7 0.7) (thickness 0.15)) (justify left bottom mirror))
    )
    (fp_text user "Author: Antmicro" (at -0.939 -3.399 270) (layer "B.Fab") hide
        (effects (font (size 0.7 0.7) (thickness 0.15)) (justify left bottom mirror))
    )
    (fp_text user "${REFERENCE}" (at 0 0 90) (layer "B.Fab")
        (effects (font (size 0.25 0.25) (thickness 0.04)) (justify mirror))
    )
    (fp_rect (start -0.925 0.47) (end 0.925 -0.47)
      (stroke (width 0.05) (type default)) (fill none) (layer "B.CrtYd"))
    (fp_line (start -0.494 -0.248) (end -0.494 0.25)
      (stroke (width 0.15) (type solid)) (layer "B.Fab"))
    (fp_line (start -0.494 0.25) (end 0.504 0.25)
      (stroke (width 0.15) (type solid)) (layer "B.Fab"))
    (fp_line (start 0.504 -0.248) (end -0.494 -0.248)
      (stroke (width 0.15) (type solid)) (layer "B.Fab"))
    (fp_line (start 0.504 0.25) (end 0.504 -0.248)
      (stroke (width 0.15) (type solid)) (layer "B.Fab"))
    (pad "1" smd roundrect (at -0.48 0 90) (size 0.59 0.64) (layers "B.Cu" "B.Paste" "B.Mask") (roundrect_rratio 0.25)
      (net 211 "VCC1V2") (pintype "passive"))
    (pad "2" smd roundrect (at 0.48 0 90) (size 0.59 0.64) (layers "B.Cu" "B.Paste" "B.Mask") (roundrect_rratio 0.25)
      (net 1 "GND") (pintype "passive"))
  )
	(footprint "antmicro-footprints:C_0402_1005Metric" (layer "B.Cu")
    (at 101.4 122.15)
    (descr "Capacitor SMD 0402")
    (tags "capacitor SMD 0402")
    (property "Author" "Antmicro")
    (property "Dielectric" "")
    (property "License" "Apache-2.0")
    (property "MPN" "C1005X5R1E474M050BB")
    (property "Manufacturer" "TDK")
    (property "Public" "False")
    (property "Sheetfile" "fpga-power-supply.kicad_sch")
    (property "Sheetname" "FPGA power supply")
    (property "Val" "470n")
    (property "Voltage" "")
    (property "ki_description" "SMD Multilayer Ceramic Capacitor, 0.47 µF, 25 V, 0402 [1005 Metric], ± 20%, X5R, C")
    (property "ki_keywords" "0402, SMT, CAPACITOR, PASSIVE, CERAMIC, MLCC")
    (attr smd)
    (fp_text reference "C188" (at -0.07 22.205) (layer "B.SilkS")
        (effects (font (size 0.7 0.7) (thickness 0.127)) (justify mirror))
    )
    (fp_text value "C_470n_0402" (at 0 -1.17) (layer "B.Fab")
        (effects (font (size 1 1) (thickness 0.15)) (justify mirror))
    )
    (fp_text user "Author: Antmicro" (at -0.939 -3.399 180) (layer "B.Fab") hide
        (effects (font (size 0.7 0.7) (thickness 0.15)) (justify left bottom mirror))
    )
    (fp_text user "${REFERENCE}" (at 0 0) (layer "B.Fab")
        (effects (font (size 0.25 0.25) (thickness 0.04)) (justify mirror))
    )
    (fp_text user "License: Apache-2.0" (at -0.939 -5.799 180) (layer "B.Fab") hide
        (effects (font (size 0.7 0.7) (thickness 0.15)) (justify left bottom mirror))
    )
    (fp_rect (start -0.925 0.47) (end 0.925 -0.47)
      (stroke (width 0.05) (type default)) (fill none) (layer "B.CrtYd"))
    (fp_line (start -0.494 -0.248) (end -0.494 0.25)
      (stroke (width 0.15) (type solid)) (layer "B.Fab"))
    (fp_line (start -0.494 0.25) (end 0.504 0.25)
      (stroke (width 0.15) (type solid)) (layer "B.Fab"))
    (fp_line (start 0.504 -0.248) (end -0.494 -0.248)
      (stroke (width 0.15) (type solid)) (layer "B.Fab"))
    (fp_line (start 0.504 0.25) (end 0.504 -0.248)
      (stroke (width 0.15) (type solid)) (layer "B.Fab"))
    (pad "1" smd roundrect (at -0.48 0) (size 0.59 0.64) (layers "B.Cu" "B.Paste" "B.Mask") (roundrect_rratio 0.25)
      (net 211 "VCC1V2") (pintype "passive"))
    (pad "2" smd roundrect (at 0.48 0) (size 0.59 0.64) (layers "B.Cu" "B.Paste" "B.Mask") (roundrect_rratio 0.25)
      (net 1 "GND") (pintype "passive"))
  )
	(footprint "antmicro-footprints:C_0402_1005Metric" (layer "B.Cu")
    (at 101.4 120.5)
    (descr "Capacitor SMD 0402")
    (tags "capacitor SMD 0402")
    (property "Author" "Antmicro")
    (property "Dielectric" "")
    (property "License" "Apache-2.0")
    (property "MPN" "C1005X5R1E474M050BB")
    (property "Manufacturer" "TDK")
    (property "Public" "False")
    (property "Sheetfile" "fpga-power-supply.kicad_sch")
    (property "Sheetname" "FPGA power supply")
    (property "Val" "470n")
    (property "Voltage" "")
    (property "ki_description" "SMD Multilayer Ceramic Capacitor, 0.47 µF, 25 V, 0402 [1005 Metric], ± 20%, X5R, C")
    (property "ki_keywords" "0402, SMT, CAPACITOR, PASSIVE, CERAMIC, MLCC")
    (attr smd)
    (fp_text reference "C189" (at -0.05 22.85) (layer "B.SilkS")
        (effects (font (size 0.7 0.7) (thickness 0.127)) (justify mirror))
    )
    (fp_text value "C_470n_0402" (at 0 -1.17) (layer "B.Fab")
        (effects (font (size 1 1) (thickness 0.15)) (justify mirror))
    )
    (fp_text user "Author: Antmicro" (at -0.939 -3.399 180) (layer "B.Fab") hide
        (effects (font (size 0.7 0.7) (thickness 0.15)) (justify left bottom mirror))
    )
    (fp_text user "License: Apache-2.0" (at -0.939 -5.799 180) (layer "B.Fab") hide
        (effects (font (size 0.7 0.7) (thickness 0.15)) (justify left bottom mirror))
    )
    (fp_text user "${REFERENCE}" (at 0 0) (layer "B.Fab")
        (effects (font (size 0.25 0.25) (thickness 0.04)) (justify mirror))
    )
    (fp_rect (start -0.925 0.47) (end 0.925 -0.47)
      (stroke (width 0.05) (type default)) (fill none) (layer "B.CrtYd"))
    (fp_line (start -0.494 -0.248) (end -0.494 0.25)
      (stroke (width 0.15) (type solid)) (layer "B.Fab"))
    (fp_line (start -0.494 0.25) (end 0.504 0.25)
      (stroke (width 0.15) (type solid)) (layer "B.Fab"))
    (fp_line (start 0.504 -0.248) (end -0.494 -0.248)
      (stroke (width 0.15) (type solid)) (layer "B.Fab"))
    (fp_line (start 0.504 0.25) (end 0.504 -0.248)
      (stroke (width 0.15) (type solid)) (layer "B.Fab"))
    (pad "1" smd roundrect (at -0.48 0) (size 0.59 0.64) (layers "B.Cu" "B.Paste" "B.Mask") (roundrect_rratio 0.25)
      (net 211 "VCC1V2") (pintype "passive"))
    (pad "2" smd roundrect (at 0.48 0) (size 0.59 0.64) (layers "B.Cu" "B.Paste" "B.Mask") (roundrect_rratio 0.25)
      (net 1 "GND") (pintype "passive"))
  )
	(footprint "antmicro-footprints:C_0402_1005Metric" (layer "B.Cu")
    (at 101.4 118.95)
    (descr "Capacitor SMD 0402")
    (tags "capacitor SMD 0402")
    (property "Author" "Antmicro")
    (property "Dielectric" "")
    (property "License" "Apache-2.0")
    (property "MPN" "C1005X5R1E474M050BB")
    (property "Manufacturer" "TDK")
    (property "Public" "False")
    (property "Sheetfile" "fpga-power-supply.kicad_sch")
    (property "Sheetname" "FPGA power supply")
    (property "Val" "470n")
    (property "Voltage" "")
    (property "ki_description" "SMD Multilayer Ceramic Capacitor, 0.47 µF, 25 V, 0402 [1005 Metric], ± 20%, X5R, C")
    (property "ki_keywords" "0402, SMT, CAPACITOR, PASSIVE, CERAMIC, MLCC")
    (attr smd)
    (fp_text reference "C190" (at -0.05 22.85) (layer "B.SilkS")
        (effects (font (size 0.7 0.7) (thickness 0.127)) (justify mirror))
    )
    (fp_text value "C_470n_0402" (at 0 -1.17) (layer "B.Fab")
        (effects (font (size 1 1) (thickness 0.15)) (justify mirror))
    )
    (fp_text user "Author: Antmicro" (at -0.939 -3.399 180) (layer "B.Fab") hide
        (effects (font (size 0.7 0.7) (thickness 0.15)) (justify left bottom mirror))
    )
    (fp_text user "License: Apache-2.0" (at -0.939 -5.799 180) (layer "B.Fab") hide
        (effects (font (size 0.7 0.7) (thickness 0.15)) (justify left bottom mirror))
    )
    (fp_text user "${REFERENCE}" (at 0 0) (layer "B.Fab")
        (effects (font (size 0.25 0.25) (thickness 0.04)) (justify mirror))
    )
    (fp_rect (start -0.925 0.47) (end 0.925 -0.47)
      (stroke (width 0.05) (type default)) (fill none) (layer "B.CrtYd"))
    (fp_line (start -0.494 -0.248) (end -0.494 0.25)
      (stroke (width 0.15) (type solid)) (layer "B.Fab"))
    (fp_line (start -0.494 0.25) (end 0.504 0.25)
      (stroke (width 0.15) (type solid)) (layer "B.Fab"))
    (fp_line (start 0.504 -0.248) (end -0.494 -0.248)
      (stroke (width 0.15) (type solid)) (layer "B.Fab"))
    (fp_line (start 0.504 0.25) (end 0.504 -0.248)
      (stroke (width 0.15) (type solid)) (layer "B.Fab"))
    (pad "1" smd roundrect (at -0.48 0) (size 0.59 0.64) (layers "B.Cu" "B.Paste" "B.Mask") (roundrect_rratio 0.25)
      (net 211 "VCC1V2") (pintype "passive"))
    (pad "2" smd roundrect (at 0.48 0) (size 0.59 0.64) (layers "B.Cu" "B.Paste" "B.Mask") (roundrect_rratio 0.25)
      (net 1 "GND") (pintype "passive"))
  )
	(footprint "antmicro-footprints:C_0402_1005Metric" (layer "B.Cu")
    (at 101.95 117.05 -90)
    (descr "Capacitor SMD 0402")
    (tags "capacitor SMD 0402")
    (property "Author" "Antmicro")
    (property "Dielectric" "")
    (property "License" "Apache-2.0")
    (property "MPN" "C1005X5R1E474M050BB")
    (property "Manufacturer" "TDK")
    (property "Public" "False")
    (property "Sheetfile" "fpga-power-supply.kicad_sch")
    (property "Sheetname" "FPGA power supply")
    (property "Val" "470n")
    (property "Voltage" "")
    (property "ki_description" "SMD Multilayer Ceramic Capacitor, 0.47 µF, 25 V, 0402 [1005 Metric], ± 20%, X5R, C")
    (property "ki_keywords" "0402, SMT, CAPACITOR, PASSIVE, CERAMIC, MLCC")
    (attr smd)
    (fp_text reference "C191" (at 22.65 0.05 90) (layer "B.SilkS")
        (effects (font (size 0.7 0.7) (thickness 0.127)) (justify mirror))
    )
    (fp_text value "C_470n_0402" (at 0 -1.17 90) (layer "B.Fab")
        (effects (font (size 1 1) (thickness 0.15)) (justify mirror))
    )
    (fp_text user "Author: Antmicro" (at -0.939 -3.399 90) (layer "B.Fab") hide
        (effects (font (size 0.7 0.7) (thickness 0.15)) (justify left bottom mirror))
    )
    (fp_text user "${REFERENCE}" (at 0 0 90) (layer "B.Fab")
        (effects (font (size 0.25 0.25) (thickness 0.04)) (justify mirror))
    )
    (fp_text user "License: Apache-2.0" (at -0.939 -5.799 90) (layer "B.Fab") hide
        (effects (font (size 0.7 0.7) (thickness 0.15)) (justify left bottom mirror))
    )
    (fp_rect (start -0.925 0.47) (end 0.925 -0.47)
      (stroke (width 0.05) (type default)) (fill none) (layer "B.CrtYd"))
    (fp_line (start -0.494 -0.248) (end -0.494 0.25)
      (stroke (width 0.15) (type solid)) (layer "B.Fab"))
    (fp_line (start -0.494 0.25) (end 0.504 0.25)
      (stroke (width 0.15) (type solid)) (layer "B.Fab"))
    (fp_line (start 0.504 -0.248) (end -0.494 -0.248)
      (stroke (width 0.15) (type solid)) (layer "B.Fab"))
    (fp_line (start 0.504 0.25) (end 0.504 -0.248)
      (stroke (width 0.15) (type solid)) (layer "B.Fab"))
    (pad "1" smd roundrect (at -0.48 0 270) (size 0.59 0.64) (layers "B.Cu" "B.Paste" "B.Mask") (roundrect_rratio 0.25)
      (net 211 "VCC1V2") (pintype "passive"))
    (pad "2" smd roundrect (at 0.48 0 270) (size 0.59 0.64) (layers "B.Cu" "B.Paste" "B.Mask") (roundrect_rratio 0.25)
      (net 1 "GND") (pintype "passive"))
  )
)
